(kicad_pcb
	(version 20260206)
	(generator "pcbnew")
	(generator_version "10.0")
	(general
		(thickness 1.6)
		(legacy_teardrops no)
	)
	(paper "A4")
	(title_block
		(title "Wiwynn_Tioga_Pass_MB.brd")
		(comment 1 "Tioga Pass / footprints 4114-4120 of 4770")
	)
	(layers
		(0 "F.Cu" signal "TOP")
		(4 "In1.Cu" signal "L2GND")
		(6 "In2.Cu" signal "L3")
		(8 "In3.Cu" signal "L4GND")
		(10 "In4.Cu" signal "L5")
		(12 "In5.Cu" signal "L6GND")
		(14 "In6.Cu" signal "L7VCC")
		(16 "In7.Cu" signal "L8VCC")
		(18 "In8.Cu" signal "L9GND")
		(20 "In9.Cu" signal "L10")
		(22 "In10.Cu" signal "L11GND")
		(24 "In11.Cu" signal "L12")
		(26 "In12.Cu" signal "L13GND")
		(2 "B.Cu" signal "BOTTOM")
		(9 "F.Adhes" user "F.Adhesive")
		(11 "B.Adhes" user "B.Adhesive")
		(13 "F.Paste" user "Package Geometry/Pastemask Top")
		(15 "B.Paste" user "Package Geometry/Pastemask Bottom")
		(5 "F.SilkS" user "Ref Des/Silkscreen Top")
		(7 "B.SilkS" user "Ref Des/Silkscreen Bottom")
		(1 "F.Mask" user "Board Geometry/Soldermask Top")
		(3 "B.Mask" user "Board Geometry/Soldermask Bottom")
		(17 "Dwgs.User" user "User.Drawings")
		(19 "Cmts.User" user "User.Comments")
		(21 "Eco1.User" user "User.Eco1")
		(23 "Eco2.User" user "User.Eco2")
		(25 "Edge.Cuts" user "Board Geometry/Outline")
		(27 "Margin" user)
		(31 "F.CrtYd" user "Package Geometry/Place Bound Top")
		(29 "B.CrtYd" user "Package Geometry/Place Bound Bottom")
		(35 "F.Fab" user "Ref Des/Assembly Top")
		(33 "B.Fab" user "Ref Des/Assembly Bottom")
	)
	(footprint ""
		(layer "B.Cu")
		(at 420.624 -151.765 90)
		(property "Reference" "C2L13"
			(at 0 0 90)
			(layer "B.SilkS")
			(hide yes)
			(effects
				(font
					(size 1.27 1.27)
				)
				(justify mirror)
			)
		)
		(property "Value" ""
			(at 0 0 90)
			(layer "B.Fab")
			(effects
				(font
					(size 1.27 1.27)
				)
				(justify mirror)
			)
		)
		(duplicate_pad_numbers_are_jumpers no)
		(fp_poly
			(pts
				(xy -0.3048 -0.1016) (xy -0.3048 0.9906) (xy 0.3048 0.9906) (xy 0.3048 -0.1016)
			)
			(stroke
				(width 0)
				(type default)
			)
			(fill no)
			(layer "B.CrtYd")
		)
		(fp_line
			(start 0.3048 -0.1016)
			(end 0.3048 0.9906)
			(stroke
				(width 0.1)
				(type default)
			)
			(layer "B.Fab")
		)
		(fp_line
			(start -0.3048 -0.1016)
			(end 0.3048 -0.1016)
			(stroke
				(width 0.1)
				(type default)
			)
			(layer "B.Fab")
		)
		(fp_line
			(start 0.3048 0.9906)
			(end -0.3048 0.9906)
			(stroke
				(width 0.1)
				(type default)
			)
			(layer "B.Fab")
		)
		(fp_line
			(start -0.3048 0.9906)
			(end -0.3048 -0.1016)
			(stroke
				(width 0.1)
				(type default)
			)
			(layer "B.Fab")
		)
		(pad "1" smd rect
			(at 0 0 270)
			(size 0.508 0.508)
			(layers "B.Cu" "B.Mask" "B.Paste")
			(net "SATA6G_PCH_PCIE_UP_SATA_RXN<2>")
		)
		(pad "2" smd rect
			(at 0 0.889 270)
			(size 0.508 0.508)
			(layers "B.Cu" "B.Mask" "B.Paste")
			(net "SATA6G_P2_RX_C_DN")
		)
		(zone
			(layer "B.Cu")
			(hatch none 0.5)
			(connect_pads
				(clearance 0)
			)
			(min_thickness 0.25)
			(keepout
				(tracks allowed)
				(vias not_allowed)
				(pads allowed)
				(copperpour not_allowed)
				(footprints allowed)
			)
			(placement
				(enabled no)
				(sheetname "")
			)
			(fill
				(thermal_gap 0.5)
				(thermal_bridge_width 0.5)
				(island_removal_mode 0)
			)
			(polygon
				(pts
					(xy 420.878 -152.019) (xy 420.878 -151.511) (xy 421.259 -151.511) (xy 421.259 -152.019)
				)
			)
		)
		(zone
			(layer "B.Cu")
			(hatch none 0.5)
			(connect_pads
				(clearance 0)
			)
			(min_thickness 0.25)
			(keepout
				(tracks not_allowed)
				(vias allowed)
				(pads allowed)
				(copperpour not_allowed)
				(footprints allowed)
			)
			(placement
				(enabled no)
				(sheetname "")
			)
			(fill
				(thermal_gap 0.5)
				(thermal_bridge_width 0.5)
				(island_removal_mode 0)
			)
			(polygon
				(pts
					(xy 421.259 -152.019) (xy 421.259 -151.511) (xy 420.878 -151.511) (xy 420.878 -152.019)
				)
			)
		)
	)
	(footprint ""
		(layer "B.Cu")
		(at 357.988616 -146.777202)
		(property "Reference" "C7W8"
			(at 0 0 0)
			(layer "B.SilkS")
			(hide yes)
			(effects
				(font
					(size 1.27 1.27)
				)
				(justify mirror)
			)
		)
		(property "Value" "*"
			(at 0.0762 -6.2357 0)
			(unlocked yes)
			(layer "B.Fab")
			(hide yes)
			(effects
				(font
					(size 1.27 1.016)
					(thickness 0.1524)
				)
				(justify mirror)
			)
		)
		(property "Device Type" "SC22U16V5MX-4-GP_SMD-BCG5-SC22A"
			(at 0.0762 -8.2677 0)
			(unlocked yes)
			(layer "B.Fab")
			(hide yes)
			(effects
				(font
					(size 1.27 1.016)
					(thickness 0.1524)
				)
				(justify mirror)
			)
		)
		(duplicate_pad_numbers_are_jumpers no)
		(fp_line
			(start -0.635 0)
			(end 0.635 0)
			(stroke
				(width 0.508)
				(type default)
			)
			(layer "B.SilkS")
		)
		(fp_rect
			(start 0.9652 1.778)
			(end -0.9652 -1.778)
			(stroke
				(width 0)
				(type default)
			)
			(fill no)
			(layer "B.CrtYd")
		)
		(fp_poly
			(pts
				(xy 0.9652 -1.778) (xy -0.9652 -1.778) (xy -0.9652 1.778) (xy 0.9652 1.778)
			)
			(stroke
				(width 0)
				(type default)
			)
			(fill no)
			(layer "B.Fab")
		)
		(pad "1" smd rect
			(at 0 -0.9652 180)
			(size 1.397 1.143)
			(layers "B.Cu" "B.Mask" "B.Paste")
			(net "VR_FET_SW_P12V_STBY_PVDDQ_DEF")
		)
		(pad "2" smd rect
			(at 0 0.9652 180)
			(size 1.397 1.143)
			(layers "B.Cu" "B.Mask" "B.Paste")
			(net "GND")
		)
	)
	(footprint ""
		(layer "B.Cu")
		(at 452.35241 -4.614672 90)
		(property "Reference" "R1U64"
			(at 0 0 90)
			(layer "B.SilkS")
			(hide yes)
			(effects
				(font
					(size 1.27 1.27)
				)
				(justify mirror)
			)
		)
		(property "Value" ""
			(at 0 0 90)
			(layer "B.Fab")
			(effects
				(font
					(size 1.27 1.27)
				)
				(justify mirror)
			)
		)
		(duplicate_pad_numbers_are_jumpers no)
		(fp_poly
			(pts
				(xy 0.2794 -0.1016) (xy -0.2794 -0.1016) (xy -0.2794 0.990854) (xy 0.2794 0.990854)
			)
			(stroke
				(width 0)
				(type default)
			)
			(fill no)
			(layer "B.CrtYd")
		)
		(fp_line
			(start 0.2794 -0.1016)
			(end 0.2794 0.990854)
			(stroke
				(width 0.1)
				(type default)
			)
			(layer "B.Fab")
		)
		(fp_line
			(start -0.2794 -0.1016)
			(end 0.2794 -0.1016)
			(stroke
				(width 0.1)
				(type default)
			)
			(layer "B.Fab")
		)
		(fp_line
			(start 0.2794 0.990854)
			(end -0.2794 0.990854)
			(stroke
				(width 0.1)
				(type default)
			)
			(layer "B.Fab")
		)
		(fp_line
			(start -0.2794 0.990854)
			(end -0.2794 -0.1016)
			(stroke
				(width 0.1)
				(type default)
			)
			(layer "B.Fab")
		)
		(pad "1" smd rect
			(at 0 0 270)
			(size 0.508 0.508)
			(layers "B.Cu" "B.Mask" "B.Paste")
			(net "PD_IE_DEBUG_MODE")
		)
		(pad "2" smd rect
			(at 0 0.889 270)
			(size 0.508 0.508)
			(layers "B.Cu" "B.Mask" "B.Paste")
			(net "GND")
		)
		(zone
			(layer "B.Cu")
			(hatch none 0.5)
			(connect_pads
				(clearance 0)
			)
			(min_thickness 0.25)
			(keepout
				(tracks allowed)
				(vias not_allowed)
				(pads allowed)
				(copperpour not_allowed)
				(footprints allowed)
			)
			(placement
				(enabled no)
				(sheetname "")
			)
			(fill
				(thermal_gap 0.5)
				(thermal_bridge_width 0.5)
				(island_removal_mode 0)
			)
			(polygon
				(pts
					(xy 452.60641 -4.868672) (xy 452.60641 -4.360672) (xy 452.987664 -4.360672) (xy 452.987664 -4.868672)
				)
			)
		)
		(zone
			(layer "B.Cu")
			(hatch none 0.5)
			(connect_pads
				(clearance 0)
			)
			(min_thickness 0.25)
			(keepout
				(tracks not_allowed)
				(vias allowed)
				(pads allowed)
				(copperpour not_allowed)
				(footprints allowed)
			)
			(placement
				(enabled no)
				(sheetname "")
			)
			(fill
				(thermal_gap 0.5)
				(thermal_bridge_width 0.5)
				(island_removal_mode 0)
			)
			(polygon
				(pts
					(xy 452.987664 -4.868672) (xy 452.987664 -4.360672) (xy 452.60641 -4.360672) (xy 452.60641 -4.868672)
				)
			)
		)
	)
	(footprint ""
		(layer "B.Cu")
		(at 183.67629 0.139192 180)
		(property "Reference" "C6U16"
			(at 0 0 0)
			(layer "B.SilkS")
			(hide yes)
			(effects
				(font
					(size 1.27 1.27)
				)
				(justify mirror)
			)
		)
		(property "Value" ""
			(at 0 0 0)
			(layer "B.Fab")
			(effects
				(font
					(size 1.27 1.27)
				)
				(justify mirror)
			)
		)
		(duplicate_pad_numbers_are_jumpers no)
		(fp_rect
			(start 0.4953 -0.2032)
			(end -0.4953 1.6002)
			(stroke
				(width 0)
				(type default)
			)
			(fill no)
			(layer "B.CrtYd")
		)
		(fp_line
			(start 0.4953 1.6002)
			(end 0.4953 -0.2032)
			(stroke
				(width 0.1)
				(type default)
			)
			(layer "B.Fab")
		)
		(fp_line
			(start 0.4953 -0.2032)
			(end -0.4953 -0.2032)
			(stroke
				(width 0.1)
				(type default)
			)
			(layer "B.Fab")
		)
		(fp_line
			(start -0.4953 1.6002)
			(end 0.4953 1.6002)
			(stroke
				(width 0.1)
				(type default)
			)
			(layer "B.Fab")
		)
		(fp_line
			(start -0.4953 -0.2032)
			(end -0.4953 1.6002)
			(stroke
				(width 0.1)
				(type default)
			)
			(layer "B.Fab")
		)
		(pad "1" smd rect
			(at 0 0)
			(size 0.762 0.889)
			(layers "B.Cu" "B.Mask" "B.Paste")
			(net "PVDDQ_ABC")
		)
		(pad "2" smd rect
			(at 0 1.397)
			(size 0.762 0.889)
			(layers "B.Cu" "B.Mask" "B.Paste")
			(net "GND")
		)
		(zone
			(layer "B.Cu")
			(hatch none 0.5)
			(connect_pads
				(clearance 0)
			)
			(min_thickness 0.25)
			(keepout
				(tracks not_allowed)
				(vias allowed)
				(pads allowed)
				(copperpour not_allowed)
				(footprints allowed)
			)
			(placement
				(enabled no)
				(sheetname "")
			)
			(fill
				(thermal_gap 0.5)
				(thermal_bridge_width 0.5)
				(island_removal_mode 0)
			)
			(polygon
				(pts
					(xy 183.29529 -0.305308) (xy 184.05729 -0.305308) (xy 184.05729 -0.813308) (xy 183.29529 -0.813308)
				)
			)
		)
	)
	(footprint ""
		(layer "B.Cu")
		(at 101.448616 -164.9857 90)
		(property "Reference" "T1D4"
			(at 0 0 90)
			(layer "B.SilkS")
			(hide yes)
			(effects
				(font
					(size 1.27 1.27)
				)
				(justify mirror)
			)
		)
		(property "Value" "*"
			(at 3.4036 -4.46405 90)
			(unlocked yes)
			(layer "B.Fab")
			(hide yes)
			(effects
				(font
					(size 0.889 0.889)
					(thickness 0.1524)
				)
				(justify mirror)
			)
		)
		(property "Device Type" "TEST-PAD-12P-1-GP-U_DISCRET-GBA"
			(at 3.4036 -5.98805 90)
			(unlocked yes)
			(layer "B.Fab")
			(hide yes)
			(effects
				(font
					(size 0.889 0.889)
					(thickness 0.1524)
				)
				(justify mirror)
			)
		)
		(duplicate_pad_numbers_are_jumpers no)
		(fp_line
			(start 2.3876 -4.826)
			(end -2.3622 -4.826)
			(stroke
				(width 0.1524)
				(type default)
			)
			(layer "B.SilkS")
		)
		(fp_line
			(start -2.3622 -4.826)
			(end -2.3622 3.4798)
			(stroke
				(width 0.1524)
				(type default)
			)
			(layer "B.SilkS")
		)
		(fp_line
			(start 2.3876 3.4798)
			(end 2.3876 -4.826)
			(stroke
				(width 0.1524)
				(type default)
			)
			(layer "B.SilkS")
		)
		(fp_line
			(start -2.3622 3.4798)
			(end 2.3876 3.4798)
			(stroke
				(width 0.1524)
				(type default)
			)
			(layer "B.SilkS")
		)
		(fp_rect
			(start 2.6416 3.7338)
			(end -2.6162 -5.08)
			(stroke
				(width 0)
				(type default)
			)
			(fill no)
			(layer "B.CrtYd")
		)
		(fp_rect
			(start 2.6416 3.7338)
			(end -2.6162 -5.08)
			(stroke
				(width 0)
				(type default)
			)
			(fill no)
			(layer "B.Fab")
		)
		(pad "1" smd circle
			(at -0.496824 -1.301496 270)
			(size 0.6604 0.6604)
			(layers "B.Cu" "B.Mask" "B.Paste")
			(net "L3_85OHM_5INCH_DN")
		)
		(pad "2" smd circle
			(at 0.503936 -1.301496 270)
			(size 0.6604 0.6604)
			(layers "B.Cu" "B.Mask" "B.Paste")
			(net "L3_85OHM_5INCH_DP")
		)
		(pad "3" smd custom
			(at 0.00889 0.370078 270)
			(size 0.74295 0.74295)
			(layers "B.Cu" "B.Mask" "B.Paste")
			(net "GND")
			(options
				(clearance outline)
				(anchor circle)
			)
			(primitives
				(gr_poly
					(pts
						(xy -2.1209 -1.4859) (xy 2.1209 -1.4859) (xy 2.1209 1.4859) (xy 1.08585 1.4859) (xy 1.08585 0.4699)
						(xy -1.08585 0.4699) (xy -1.08585 1.4859) (xy -2.1209 1.4859)
					)
					(width 0)
					(fill yes)
				)
			)
		)
		(pad "4" thru_hole circle
			(at -1.266444 -3.851656 270)
			(size 1.4478 1.4478)
			(drill 1.0414)
			(layers "*.Cu" "*.Mask")
			(remove_unused_layers no)
			(net "GND")
			(clearance 0.1524)
			(thermal_gap 0.1524)
		)
		(pad "5" thru_hole circle
			(at 1.273556 -3.851656 270)
			(size 1.4478 1.4478)
			(drill 1.0414)
			(layers "*.Cu" "*.Mask")
			(remove_unused_layers no)
			(net "GND")
			(clearance 0.1524)
			(thermal_gap 0.1524)
		)
		(pad "6" thru_hole circle
			(at -1.266444 2.498344 270)
			(size 1.4478 1.4478)
			(drill 1.0414)
			(layers "*.Cu" "*.Mask")
			(remove_unused_layers no)
			(net "GND")
			(clearance 0.1524)
			(thermal_gap 0.1524)
		)
		(pad "7" thru_hole circle
			(at 1.273556 2.498344 270)
			(size 1.4478 1.4478)
			(drill 1.0414)
			(layers "*.Cu" "*.Mask")
			(remove_unused_layers no)
			(net "GND")
			(clearance 0.1524)
			(thermal_gap 0.1524)
		)
		(pad "8" thru_hole circle
			(at -1.27 -0.4572 270)
			(size 0.7112 0.7112)
			(drill 0.4064)
			(layers "*.Cu" "*.Mask")
			(remove_unused_layers no)
			(net "GND")
			(clearance 0.1016)
			(thermal_gap 0.1016)
		)
		(pad "9" thru_hole circle
			(at -1.27 0.762 270)
			(size 0.7112 0.7112)
			(drill 0.4064)
			(layers "*.Cu" "*.Mask")
			(remove_unused_layers no)
			(net "GND")
			(clearance 0.1016)
			(thermal_gap 0.1016)
		)
		(pad "10" thru_hole circle
			(at 0.0254 0.762 270)
			(size 0.7112 0.7112)
			(drill 0.4064)
			(layers "*.Cu" "*.Mask")
			(remove_unused_layers no)
			(net "GND")
			(clearance 0.1016)
			(thermal_gap 0.1016)
		)
		(pad "11" thru_hole circle
			(at 1.27 0.762 270)
			(size 0.7112 0.7112)
			(drill 0.4064)
			(layers "*.Cu" "*.Mask")
			(remove_unused_layers no)
			(net "GND")
			(clearance 0.1016)
			(thermal_gap 0.1016)
		)
		(pad "12" thru_hole circle
			(at 1.27 -0.4572 270)
			(size 0.7112 0.7112)
			(drill 0.4064)
			(layers "*.Cu" "*.Mask")
			(remove_unused_layers no)
			(net "GND")
			(clearance 0.1016)
			(thermal_gap 0.1016)
		)
	)
	(footprint ""
		(layer "B.Cu")
		(at 474.218 -38.354 -90)
		(property "Reference" "R9F12"
			(at 0 0 90)
			(layer "B.SilkS")
			(hide yes)
			(effects
				(font
					(size 1.27 1.27)
				)
				(justify mirror)
			)
		)
		(property "Value" ""
			(at 0 0 90)
			(layer "B.Fab")
			(effects
				(font
					(size 1.27 1.27)
				)
				(justify mirror)
			)
		)
		(duplicate_pad_numbers_are_jumpers no)
		(fp_poly
			(pts
				(xy 0.2794 -0.1016) (xy -0.2794 -0.1016) (xy -0.2794 0.9906) (xy 0.2794 0.9906)
			)
			(stroke
				(width 0)
				(type default)
			)
			(fill no)
			(layer "B.CrtYd")
		)
		(fp_line
			(start -0.2794 0.9906)
			(end -0.2794 -0.1016)
			(stroke
				(width 0.1)
				(type default)
			)
			(layer "B.Fab")
		)
		(fp_line
			(start 0.2794 0.9906)
			(end -0.2794 0.9906)
			(stroke
				(width 0.1)
				(type default)
			)
			(layer "B.Fab")
		)
		(fp_line
			(start -0.2794 -0.1016)
			(end 0.2794 -0.1016)
			(stroke
				(width 0.1)
				(type default)
			)
			(layer "B.Fab")
		)
		(fp_line
			(start 0.2794 -0.1016)
			(end 0.2794 0.9906)
			(stroke
				(width 0.1)
				(type default)
			)
			(layer "B.Fab")
		)
		(pad "1" smd rect
			(at 0 0 90)
			(size 0.508 0.508)
			(layers "B.Cu" "B.Mask" "B.Paste")
			(net "P3V3_STBY")
		)
		(pad "2" smd rect
			(at 0 0.889 90)
			(size 0.508 0.508)
			(layers "B.Cu" "B.Mask" "B.Paste")
			(net "PWRGD_P1V2_BMC_STBY_R")
		)
		(zone
			(layer "B.Cu")
			(hatch none 0.5)
			(connect_pads
				(clearance 0)
			)
			(min_thickness 0.25)
			(keepout
				(tracks not_allowed)
				(vias allowed)
				(pads allowed)
				(copperpour not_allowed)
				(footprints allowed)
			)
			(placement
				(enabled no)
				(sheetname "")
			)
			(fill
				(thermal_gap 0.5)
				(thermal_bridge_width 0.5)
				(island_removal_mode 0)
			)
			(polygon
				(pts
					(xy 473.583 -38.1) (xy 473.583 -38.608) (xy 473.964 -38.608) (xy 473.964 -38.1)
				)
			)
		)
		(zone
			(layer "B.Cu")
			(hatch none 0.5)
			(connect_pads
				(clearance 0)
			)
			(min_thickness 0.25)
			(keepout
				(tracks allowed)
				(vias not_allowed)
				(pads allowed)
				(copperpour not_allowed)
				(footprints allowed)
			)
			(placement
				(enabled no)
				(sheetname "")
			)
			(fill
				(thermal_gap 0.5)
				(thermal_bridge_width 0.5)
				(island_removal_mode 0)
			)
			(polygon
				(pts
					(xy 473.964 -38.1) (xy 473.964 -38.608) (xy 473.583 -38.608) (xy 473.583 -38.1)
				)
			)
		)
	)
	(footprint ""
		(layer "B.Cu")
		(at 248.8565 -17.7546 -90)
		(property "Reference" "C5T11"
			(at -1.848866 0.752348 270)
			(unlocked yes)
			(layer "B.SilkS")
			(effects
				(font
					(size 1.27 0.9652)
					(thickness 0.1524)
				)
				(justify mirror)
			)
		)
		(property "Value" ""
			(at 0 0 90)
			(layer "B.Fab")
			(effects
				(font
					(size 1.27 1.27)
				)
				(justify mirror)
			)
		)
		(duplicate_pad_numbers_are_jumpers no)
		(fp_rect
			(start 0.500126 1.598422)
			(end -0.500126 -0.201422)
			(stroke
				(width 0)
				(type default)
			)
			(fill no)
			(layer "B.CrtYd")
		)
		(fp_line
			(start -0.500126 1.598422)
			(end 0.500126 1.598422)
			(stroke
				(width 0.1)
				(type default)
			)
			(layer "B.Fab")
		)
		(fp_line
			(start 0.500126 1.598422)
			(end 0.500126 -0.201422)
			(stroke
				(width 0.1)
				(type default)
			)
			(layer "B.Fab")
		)
		(fp_line
			(start -0.500126 -0.201422)
			(end -0.500126 1.598422)
			(stroke
				(width 0.1)
				(type default)
			)
			(layer "B.Fab")
		)
		(fp_line
			(start 0.500126 -0.201422)
			(end -0.500126 -0.201422)
			(stroke
				(width 0.1)
				(type default)
			)
			(layer "B.Fab")
		)
		(pad "1" smd rect
			(at 0 0 180)
			(size 0.889 0.9906)
			(layers "B.Cu" "B.Mask" "B.Paste")
			(net "PVDDQ_ABC")
		)
		(pad "2" smd rect
			(at 0 1.397 180)
			(size 0.889 0.9906)
			(layers "B.Cu" "B.Mask" "B.Paste")
			(net "GND")
		)
		(zone
			(layer "B.Cu")
			(hatch none 0.5)
			(connect_pads
				(clearance 0)
			)
			(min_thickness 0.25)
			(keepout
				(tracks not_allowed)
				(vias allowed)
				(pads allowed)
				(copperpour not_allowed)
				(footprints allowed)
			)
			(placement
				(enabled no)
				(sheetname "")
			)
			(fill
				(thermal_gap 0.5)
				(thermal_bridge_width 0.5)
				(island_removal_mode 0)
			)
			(polygon
				(pts
					(xy 247.904 -17.2593) (xy 248.412 -17.2593) (xy 248.412 -18.2499) (xy 247.904 -18.2499)
				)
			)
		)
		(zone
			(layer "B.Cu")
			(hatch none 0.5)
			(connect_pads
				(clearance 0)
			)
			(min_thickness 0.25)
			(keepout
				(tracks allowed)
				(vias not_allowed)
				(pads allowed)
				(copperpour not_allowed)
				(footprints allowed)
			)
			(placement
				(enabled no)
				(sheetname "")
			)
			(fill
				(thermal_gap 0.5)
				(thermal_bridge_width 0.5)
				(island_removal_mode 0)
			)
			(polygon
				(pts
					(xy 247.904 -17.2593) (xy 248.412 -17.2593) (xy 248.412 -18.2499) (xy 247.904 -18.2499)
				)
			)
		)
	)
)
